# S9S_MB_2U (Grand Teton) — schematic netlist excerpt (pin names and nets, part order shuffled) for the footprints in the layout excerpt that follows; sources: Cadence DE-HDL packaged netlist, KiCad conversion of 03242023_DA0F0TMBIJ0_F0T_Motherboard_J_brd_V01_OCP.brd

D90  Q_LED  IC  pkg SMLF  page 255 : A = LED_RST_PLTRST_N ; C = LED_RST_PLTRST_N_D

(kicad_pcb
	(version 20260206)
	(generator "pcbnew")
	(generator_version "10.0")
	(general
		(thickness 1.6)
		(legacy_teardrops no)
	)
	(paper "A4")
	(title_block
		(title "03242023_DA0F0TMBIJ0_F0T_Motherboard_J_brd_V01_OCP.brd")
		(comment 1 "Grand Teton / footprints 1842-1842 of 6105")
	)
	(layers
		(0 "F.Cu" signal "TOP")
		(4 "In1.Cu" signal "GND")
		(6 "In2.Cu" signal "IN1")
		(8 "In3.Cu" signal "GND1")
		(10 "In4.Cu" signal "IN2")
		(12 "In5.Cu" signal "GND2")
		(14 "In6.Cu" signal "IN3")
		(16 "In7.Cu" signal "GND3")
		(18 "In8.Cu" signal "VCC")
		(20 "In9.Cu" signal "VCC1")
		(22 "In10.Cu" signal "GND4")
		(24 "In11.Cu" signal "IN4")
		(26 "In12.Cu" signal "GND5")
		(28 "In13.Cu" signal "IN5")
		(30 "In14.Cu" signal "GND6")
		(32 "In15.Cu" signal "IN6")
		(34 "In16.Cu" signal "GND7")
		(2 "B.Cu" signal "BOTTOM")
		(9 "F.Adhes" user "F.Adhesive")
		(11 "B.Adhes" user "B.Adhesive")
		(13 "F.Paste" user "Package Geometry/Pastemask Top")
		(15 "B.Paste" user "Package Geometry/Pastemask Bottom")
		(5 "F.SilkS" user "Ref Des/Silkscreen Top")
		(7 "B.SilkS" user "Ref Des/Silkscreen Bottom")
		(1 "F.Mask" user "Board Geometry/Soldermask Top")
		(3 "B.Mask" user "Board Geometry/Soldermask Bottom")
		(17 "Dwgs.User" user "User.Drawings")
		(19 "Cmts.User" user "User.Comments")
		(21 "Eco1.User" user "User.Eco1")
		(23 "Eco2.User" user "User.Eco2")
		(25 "Edge.Cuts" user "Board Geometry/Outline")
		(27 "Margin" user)
		(31 "F.CrtYd" user "Package Geometry/Place Bound Top")
		(29 "B.CrtYd" user "Package Geometry/Place Bound Bottom")
		(35 "F.Fab" user "Ref Des/Assembly Top")
		(33 "B.Fab" user "Ref Des/Assembly Bottom")
	)
	(footprint ""
		(layer "F.Cu")
		(at 84.181696 -70.78599)
		(property "Reference" "D90"
			(at -43.164506 50.178462 90)
			(unlocked yes)
			(layer "F.SilkS")
			(effects
				(font
					(size 0.635 0.4064)
					(thickness 0.1524)
				)
				(justify left)
			)
		)
		(property "Value" ""
			(at 0 0 0)
			(layer "F.Fab")
			(effects
				(font
					(size 1.27 1.27)
				)
			)
		)
		(duplicate_pad_numbers_are_jumpers no)
		(fp_line
			(start -0.90678 0.4826)
			(end -0.90678 -0.4699)
			(stroke
				(width 0.1524)
				(type default)
			)
			(layer "F.SilkS")
		)
		(fp_line
			(start -0.89408 -0.4826)
			(end 0.90678 -0.4826)
			(stroke
				(width 0.1524)
				(type default)
			)
			(layer "F.SilkS")
		)
		(fp_line
			(start -0.79248 -0.4826)
			(end 1.03378 -0.4826)
			(stroke
				(width 0.1524)
				(type default)
			)
			(layer "F.SilkS")
		)
		(fp_line
			(start -0.64008 -0.4826)
			(end 1.16078 -0.4826)
			(stroke
				(width 0.1524)
				(type default)
			)
			(layer "F.SilkS")
		)
		(fp_line
			(start 0.90678 -0.4826)
			(end 0.90678 0.4826)
			(stroke
				(width 0.1524)
				(type default)
			)
			(layer "F.SilkS")
		)
		(fp_line
			(start 0.90678 0.4826)
			(end -0.90678 0.4826)
			(stroke
				(width 0.1524)
				(type default)
			)
			(layer "F.SilkS")
		)
		(fp_line
			(start 1.03378 -0.4826)
			(end 1.03378 0.4826)
			(stroke
				(width 0.1524)
				(type default)
			)
			(layer "F.SilkS")
		)
		(fp_line
			(start 1.03378 0.4826)
			(end -0.79248 0.4826)
			(stroke
				(width 0.1524)
				(type default)
			)
			(layer "F.SilkS")
		)
		(fp_line
			(start 1.16078 -0.4826)
			(end 1.16078 0.4826)
			(stroke
				(width 0.1524)
				(type default)
			)
			(layer "F.SilkS")
		)
		(fp_line
			(start 1.16078 0.4826)
			(end -0.64008 0.4826)
			(stroke
				(width 0.1524)
				(type default)
			)
			(layer "F.SilkS")
		)
		(fp_line
			(start -0.499872 -0.249936)
			(end 0.499872 -0.249936)
			(stroke
				(width 0.1)
				(type default)
			)
			(layer "F.Fab")
		)
		(fp_line
			(start -0.499872 0.249936)
			(end -0.499872 -0.249936)
			(stroke
				(width 0.1)
				(type default)
			)
			(layer "F.Fab")
		)
		(fp_line
			(start 0.499872 -0.249936)
			(end 0.499872 0.249936)
			(stroke
				(width 0.1)
				(type default)
			)
			(layer "F.Fab")
		)
		(fp_line
			(start 0.499872 0.249936)
			(end -0.499872 0.249936)
			(stroke
				(width 0.1)
				(type default)
			)
			(layer "F.Fab")
		)
		(pad "A" smd rect
			(at -0.47498 0)
			(size 0.6096 0.7112)
			(layers "F.Cu" "F.Mask" "F.Paste")
			(net "LED_RST_PLTRST_N")
		)
		(pad "C" smd rect
			(at 0.47498 0)
			(size 0.6096 0.7112)
			(layers "F.Cu" "F.Mask" "F.Paste")
			(net "LED_RST_PLTRST_N_D")
		)
	)
)
